#ISCELL
  mstr_misc prelim *
  *
#ISCELL
  mstr_symbols design_note *
  *
#ISCELL
  mstr_symbols intel_corp_bpage *
  *
#ISCELL
  mstr_standard tap *
  page66_i10
#ISCELL
  mstr_standard tap *
  page66_i11
#ISCELL
  mstr_standard tap *
  page66_i12
#ISCELL
  mstr_standard tap *
  page66_i13
#ISCELL
  mstr_standard tap *
  page66_i14
#ISCELL
  mstr_standard tap *
  page66_i15
#ISCELL
  mstr_standard tap *
  page66_i16
#ISCELL
  mstr_standard tap *
  page66_i17
#ISCELL
  mstr_standard tap *
  page66_i18
#ISCELL
  mstr_standard tap *
  page66_i19
#ISCELL
  mstr_standard tap *
  page66_i20
#ISCELL
  mstr_standard tap *
  page66_i21
#ISCELL
  mstr_standard tap *
  page66_i22
#ISCELL
  mstr_standard tap *
  page66_i23
#ISCELL
  mstr_standard tap *
  page66_i24
#ISCELL
  mstr_standard tap *
  page66_i25
#ISCELL
  mstr_standard tap *
  page66_i26
#ISCELL
  mstr_standard tap *
  page66_i27
#ISCELL
  mstr_standard tap *
  page66_i28
#ISCELL
  mstr_standard tap *
  page66_i29
#ISCELL
  mstr_standard tap *
  page66_i30
#ISCELL
  mstr_standard tap *
  page66_i31
#ISCELL
  mstr_standard tap *
  page66_i32
#ISCELL
  mstr_standard tap *
  page66_i33
#ISCELL
  mstr_standard tap *
  page66_i34
#ISCELL
  mstr_standard tap *
  page66_i35
#ISCELL
  mstr_standard tap *
  page66_i36
#ISCELL
  mstr_standard tap *
  page66_i37
#ISCELL
  mstr_standard tap *
  page66_i38
#ISCELL
  mstr_standard tap *
  page66_i39
#ISCELL
  mstr_standard tap *
  page66_i40
#ISCELL
  mstr_standard tap *
  page66_i41
#ISCELL
  mstr_standard tap *
  page66_i42
#ISCELL
  mstr_standard tap *
  page66_i43
#ISCELL
  mstr_standard tap *
  page66_i44
#ISCELL
  mstr_standard tap *
  page66_i45
#ISCELL
  mstr_standard tap *
  page66_i46
#ISCELL
  mstr_standard tap *
  page66_i47
#ISCELL
  mstr_standard tap *
  page66_i48
#ISCELL
  mstr_standard tap *
  page66_i49
#ISCELL
  mstr_standard tap *
  page66_i50
#ISCELL
  mstr_standard tap *
  page66_i51
#ISCELL
  mstr_standard tap *
  page66_i52
#ISCELL
  mstr_standard tap *
  page66_i53
#ISCELL
  mstr_standard tap *
  page66_i54
#ISCELL
  mstr_standard tap *
  page66_i55
#ISCELL
  mstr_standard tap *
  page66_i56
#ISCELL
  mstr_standard tap *
  page66_i57
#ISCELL
  mstr_standard tap *
  page66_i58
#ISCELL
  mstr_standard tap *
  page66_i59
#ISCELL
  mstr_standard tap *
  page66_i60
#ISCELL
  mstr_standard tap *
  page66_i61
#ISCELL
  mstr_standard tap *
  page66_i62
#ISCELL
  mstr_standard tap *
  page66_i63
#ISCELL
  mstr_standard tap *
  page66_i64
#ISCELL
  mstr_standard tap *
  page66_i65
#ISCELL
  mstr_standard tap *
  page66_i66
#ISCELL
  mstr_standard tap *
  page66_i67
#ISCELL
  mstr_standard tap *
  page66_i68
#ISCELL
  mstr_standard tap *
  page66_i69
#ISCELL
  mstr_standard tap *
  page66_i70
#ISCELL
  mstr_standard tap *
  page66_i71
#ISCELL
  mstr_standard tap *
  page66_i72
#ISCELL
  mstr_standard tap *
  page66_i73
#ISCELL
  mstr_standard offpage *
  page66_i75
#ISCELL
  mstr_standard offpage *
  page66_i76
#ISCELL
  mstr_standard offpage *
  page66_i77
#ISCELL
  mstr_standard offpage *
  page66_i78
#ISCELL
  mstr_standard offpage *
  page66_i80
#ISCELL
  mstr_standard offpage *
  page66_i81
#ISCELL
  mstr_standard offpage *
  page66_i82
#ISCELL
  mstr_standard offpage *
  page66_i83
#CELL
  chpset_lib skx_ext_b *
  page66_i84
